# S9S_MB_2U (Grand Teton) — schematic netlist excerpt (pin names and nets, part order shuffled) for the footprints in the layout excerpt that follows; sources: Cadence DE-HDL packaged netlist, KiCad conversion of 03242023_DA0F0TMBIJ0_F0T_Motherboard_J_brd_V01_OCP.brd

PR2512  Q_RES  1 1% EMPTY  pkg 0402LF  page 304 : A = P12V_HSC_ADC_P ; B = P12V_HSC_SENSE2_R3_P
C60  Q_CAP  10UF 16V 10% X6S  pkg C0805  page 101 : A = P12V_S3_AUX_CPU1_NVDIMM ; B = GND
R1200  Q_RES  100 1% CHIP  pkg 0402LF  page 182 : A = FM_PCH_TRIGGER0_N ; B = FM_PCH_TRIGGER0_R_N

(kicad_pcb
	(version 20260206)
	(generator "pcbnew")
	(generator_version "10.0")
	(general
		(thickness 1.6)
		(legacy_teardrops no)
	)
	(paper "A4")
	(title_block
		(title "03242023_DA0F0TMBIJ0_F0T_Motherboard_J_brd_V01_OCP.brd")
		(comment 1 "Grand Teton / footprints 4446-4448 of 6105")
	)
	(layers
		(0 "F.Cu" signal "TOP")
		(4 "In1.Cu" signal "GND")
		(6 "In2.Cu" signal "IN1")
		(8 "In3.Cu" signal "GND1")
		(10 "In4.Cu" signal "IN2")
		(12 "In5.Cu" signal "GND2")
		(14 "In6.Cu" signal "IN3")
		(16 "In7.Cu" signal "GND3")
		(18 "In8.Cu" signal "VCC")
		(20 "In9.Cu" signal "VCC1")
		(22 "In10.Cu" signal "GND4")
		(24 "In11.Cu" signal "IN4")
		(26 "In12.Cu" signal "GND5")
		(28 "In13.Cu" signal "IN5")
		(30 "In14.Cu" signal "GND6")
		(32 "In15.Cu" signal "IN6")
		(34 "In16.Cu" signal "GND7")
		(2 "B.Cu" signal "BOTTOM")
		(9 "F.Adhes" user "F.Adhesive")
		(11 "B.Adhes" user "B.Adhesive")
		(13 "F.Paste" user "Package Geometry/Pastemask Top")
		(15 "B.Paste" user "Package Geometry/Pastemask Bottom")
		(5 "F.SilkS" user "Ref Des/Silkscreen Top")
		(7 "B.SilkS" user "Ref Des/Silkscreen Bottom")
		(1 "F.Mask" user "Board Geometry/Soldermask Top")
		(3 "B.Mask" user "Board Geometry/Soldermask Bottom")
		(17 "Dwgs.User" user "User.Drawings")
		(19 "Cmts.User" user "User.Comments")
		(21 "Eco1.User" user "User.Eco1")
		(23 "Eco2.User" user "User.Eco2")
		(25 "Edge.Cuts" user "Board Geometry/Outline")
		(27 "Margin" user)
		(31 "F.CrtYd" user "Package Geometry/Place Bound Top")
		(29 "B.CrtYd" user "Package Geometry/Place Bound Bottom")
		(35 "F.Fab" user "Ref Des/Assembly Top")
		(33 "B.Fab" user "Ref Des/Assembly Bottom")
	)
	(footprint ""
		(layer "B.Cu")
		(at 322.984622 -57.267348 180)
		(property "Reference" "R1200"
			(at 0 0 0)
			(layer "B.SilkS")
			(hide yes)
			(effects
				(font
					(size 1.27 1.27)
				)
				(justify mirror)
			)
		)
		(property "Value" ""
			(at 0 0 0)
			(layer "B.Fab")
			(effects
				(font
					(size 1.27 1.27)
				)
				(justify mirror)
			)
		)
		(duplicate_pad_numbers_are_jumpers no)
		(fp_line
			(start 0.7874 0.4064)
			(end 0.7874 -0.4064)
			(stroke
				(width 0.1524)
				(type default)
			)
			(layer "B.SilkS")
		)
		(fp_line
			(start 0.7874 -0.4064)
			(end -0.7874 -0.4064)
			(stroke
				(width 0.1524)
				(type default)
			)
			(layer "B.SilkS")
		)
		(fp_line
			(start -0.7874 0.4064)
			(end 0.7874 0.4064)
			(stroke
				(width 0.1524)
				(type default)
			)
			(layer "B.SilkS")
		)
		(fp_line
			(start -0.7874 -0.4064)
			(end -0.7874 0.4064)
			(stroke
				(width 0.1524)
				(type default)
			)
			(layer "B.SilkS")
		)
		(fp_line
			(start 0.67945 0.3048)
			(end 0.67945 -0.305054)
			(stroke
				(width 0.1)
				(type default)
			)
			(layer "B.Fab")
		)
		(fp_line
			(start 0.67945 -0.305054)
			(end 0.12065 -0.305054)
			(stroke
				(width 0.1)
				(type default)
			)
			(layer "B.Fab")
		)
		(fp_line
			(start 0.12065 0.3048)
			(end 0.67945 0.3048)
			(stroke
				(width 0.1)
				(type default)
			)
			(layer "B.Fab")
		)
		(fp_line
			(start 0.12065 0.2794)
			(end 0.12065 0.3048)
			(stroke
				(width 0.1)
				(type default)
			)
			(layer "B.Fab")
		)
		(fp_line
			(start 0.12065 -0.2794)
			(end -0.12065 -0.2794)
			(stroke
				(width 0.1)
				(type default)
			)
			(layer "B.Fab")
		)
		(fp_line
			(start 0.12065 -0.305054)
			(end 0.12065 -0.2794)
			(stroke
				(width 0.1)
				(type default)
			)
			(layer "B.Fab")
		)
		(fp_line
			(start -0.120396 0.3048)
			(end -0.120396 0.2794)
			(stroke
				(width 0.1)
				(type default)
			)
			(layer "B.Fab")
		)
		(fp_line
			(start -0.120396 0.2794)
			(end 0.12065 0.2794)
			(stroke
				(width 0.1)
				(type default)
			)
			(layer "B.Fab")
		)
		(fp_line
			(start -0.12065 -0.2794)
			(end -0.12065 -0.3048)
			(stroke
				(width 0.1)
				(type default)
			)
			(layer "B.Fab")
		)
		(fp_line
			(start -0.12065 -0.3048)
			(end -0.67945 -0.3048)
			(stroke
				(width 0.1)
				(type default)
			)
			(layer "B.Fab")
		)
		(fp_line
			(start -0.67945 0.3048)
			(end -0.120396 0.3048)
			(stroke
				(width 0.1)
				(type default)
			)
			(layer "B.Fab")
		)
		(fp_line
			(start -0.67945 -0.3048)
			(end -0.67945 0.3048)
			(stroke
				(width 0.1)
				(type default)
			)
			(layer "B.Fab")
		)
		(pad "1" smd circle
			(at 0.40005 0)
			(size 0 0)
			(layers "B.Cu" "B.Mask" "B.Paste")
			(net "FM_PCH_TRIGGER0_N")
		)
		(pad "2" smd circle
			(at -0.40005 0)
			(size 0 0)
			(layers "B.Cu" "B.Mask" "B.Paste")
			(net "FM_PCH_TRIGGER0_R_N")
		)
	)
	(footprint ""
		(layer "B.Cu")
		(at 49.936146 -321.554856 -90)
		(property "Reference" "C60"
			(at 0 0 90)
			(layer "B.SilkS")
			(hide yes)
			(effects
				(font
					(size 1.27 1.27)
				)
				(justify mirror)
			)
		)
		(property "Value" ""
			(at 0 0 90)
			(layer "B.Fab")
			(effects
				(font
					(size 1.27 1.27)
				)
				(justify mirror)
			)
		)
		(duplicate_pad_numbers_are_jumpers no)
		(fp_line
			(start -1.524 0.762)
			(end 1.524 0.762)
			(stroke
				(width 0.1524)
				(type default)
			)
			(layer "B.SilkS")
		)
		(fp_line
			(start 1.524 0.762)
			(end 1.524 -0.762)
			(stroke
				(width 0.1524)
				(type default)
			)
			(layer "B.SilkS")
		)
		(fp_line
			(start -1.524 -0.762)
			(end -1.524 0.762)
			(stroke
				(width 0.1524)
				(type default)
			)
			(layer "B.SilkS")
		)
		(fp_line
			(start 1.524 -0.762)
			(end -1.524 -0.762)
			(stroke
				(width 0.1524)
				(type default)
			)
			(layer "B.SilkS")
		)
		(fp_line
			(start -1.1049 0.724916)
			(end -1.1049 -0.724916)
			(stroke
				(width 0.1)
				(type default)
			)
			(layer "B.Fab")
		)
		(fp_line
			(start 1.1049 0.724916)
			(end -1.1049 0.724916)
			(stroke
				(width 0.1)
				(type default)
			)
			(layer "B.Fab")
		)
		(fp_line
			(start -1.1049 -0.724916)
			(end 1.1049 -0.724916)
			(stroke
				(width 0.1)
				(type default)
			)
			(layer "B.Fab")
		)
		(fp_line
			(start 1.1049 -0.724916)
			(end 1.1049 0.724916)
			(stroke
				(width 0.1)
				(type default)
			)
			(layer "B.Fab")
		)
		(pad "1" smd rect
			(at 0.889 0 270)
			(size 1.016 1.27)
			(layers "B.Cu" "B.Mask" "B.Paste")
			(net "P12V_S3_AUX_CPU1_NVDIMM")
		)
		(pad "2" smd rect
			(at -0.889 0 270)
			(size 1.016 1.27)
			(layers "B.Cu" "B.Mask" "B.Paste")
			(net "GND")
		)
	)
	(footprint ""
		(layer "B.Cu")
		(at 295.93413 -403.031452 90)
		(property "Reference" "PR2512"
			(at 0 0 90)
			(layer "B.SilkS")
			(hide yes)
			(effects
				(font
					(size 1.27 1.27)
				)
				(justify mirror)
			)
		)
		(property "Value" ""
			(at 0 0 90)
			(layer "B.Fab")
			(effects
				(font
					(size 1.27 1.27)
				)
				(justify mirror)
			)
		)
		(duplicate_pad_numbers_are_jumpers no)
		(fp_line
			(start 0.7874 -0.4064)
			(end -0.7874 -0.4064)
			(stroke
				(width 0.1524)
				(type default)
			)
			(layer "B.SilkS")
		)
		(fp_line
			(start -0.7874 -0.4064)
			(end -0.7874 0.4064)
			(stroke
				(width 0.1524)
				(type default)
			)
			(layer "B.SilkS")
		)
		(fp_line
			(start 0.7874 0.4064)
			(end 0.7874 -0.4064)
			(stroke
				(width 0.1524)
				(type default)
			)
			(layer "B.SilkS")
		)
		(fp_line
			(start -0.7874 0.4064)
			(end 0.7874 0.4064)
			(stroke
				(width 0.1524)
				(type default)
			)
			(layer "B.SilkS")
		)
		(fp_line
			(start 0.67945 -0.305054)
			(end 0.12065 -0.305054)
			(stroke
				(width 0.1)
				(type default)
			)
			(layer "B.Fab")
		)
		(fp_line
			(start 0.12065 -0.305054)
			(end 0.12065 -0.2794)
			(stroke
				(width 0.1)
				(type default)
			)
			(layer "B.Fab")
		)
		(fp_line
			(start -0.12065 -0.3048)
			(end -0.67945 -0.3048)
			(stroke
				(width 0.1)
				(type default)
			)
			(layer "B.Fab")
		)
		(fp_line
			(start -0.67945 -0.3048)
			(end -0.67945 0.3048)
			(stroke
				(width 0.1)
				(type default)
			)
			(layer "B.Fab")
		)
		(fp_line
			(start 0.12065 -0.2794)
			(end -0.12065 -0.2794)
			(stroke
				(width 0.1)
				(type default)
			)
			(layer "B.Fab")
		)
		(fp_line
			(start -0.12065 -0.2794)
			(end -0.12065 -0.3048)
			(stroke
				(width 0.1)
				(type default)
			)
			(layer "B.Fab")
		)
		(fp_line
			(start 0.12065 0.2794)
			(end 0.12065 0.3048)
			(stroke
				(width 0.1)
				(type default)
			)
			(layer "B.Fab")
		)
		(fp_line
			(start -0.120396 0.2794)
			(end 0.12065 0.2794)
			(stroke
				(width 0.1)
				(type default)
			)
			(layer "B.Fab")
		)
		(fp_line
			(start 0.67945 0.3048)
			(end 0.67945 -0.305054)
			(stroke
				(width 0.1)
				(type default)
			)
			(layer "B.Fab")
		)
		(fp_line
			(start 0.12065 0.3048)
			(end 0.67945 0.3048)
			(stroke
				(width 0.1)
				(type default)
			)
			(layer "B.Fab")
		)
		(fp_line
			(start -0.120396 0.3048)
			(end -0.120396 0.2794)
			(stroke
				(width 0.1)
				(type default)
			)
			(layer "B.Fab")
		)
		(fp_line
			(start -0.67945 0.3048)
			(end -0.120396 0.3048)
			(stroke
				(width 0.1)
				(type default)
			)
			(layer "B.Fab")
		)
		(pad "1" smd circle
			(at 0.40005 0 270)
			(size 0 0)
			(layers "B.Cu" "B.Mask" "B.Paste")
			(net "P12V_HSC_ADC_P")
		)
		(pad "2" smd circle
			(at -0.40005 0 270)
			(size 0 0)
			(layers "B.Cu" "B.Mask" "B.Paste")
			(net "P12V_HSC_SENSE2_R3_P")
		)
	)
)
